# T6G (Grand Teton) — schematic netlist excerpt (pin names and nets, part order shuffled) for the footprints in the layout excerpt that follows; sources: Cadence DE-HDL packaged netlist, KiCad conversion of 04192023_DAF0TMB3IC0_F0TG_MB_C_brd_V02_OCP.brd

PC2340  Q_CAP  560PF 50V 10% X7R  pkg C0402  page 152 : A = P12V_SCM_ISET_R ; B = GND
C475  Q_CAP  100UF 4V 20% X6S  pkg C0805  page 356 : A = P0V9_CPU1_RT3_2A ; B = GND
PC302_3  Q_CAP  22UF 4V 20% X6S  pkg C0805  page 212 : A = PVDDCR_CPU0_P1 ; B = GND

(kicad_pcb
	(version 20260206)
	(generator "pcbnew")
	(generator_version "10.0")
	(general
		(thickness 1.6)
		(legacy_teardrops no)
	)
	(paper "A4")
	(title_block
		(title "04192023_DAF0TMB3IC0_F0TG_MB_C_brd_V02_OCP.brd")
		(comment 1 "Grand Teton / footprints 5629-5631 of 8354")
	)
	(layers
		(0 "F.Cu" signal "TOP")
		(4 "In1.Cu" signal "GND")
		(6 "In2.Cu" signal "IN1")
		(8 "In3.Cu" signal "GND1")
		(10 "In4.Cu" signal "IN2")
		(12 "In5.Cu" signal "GND2")
		(14 "In6.Cu" signal "IN3")
		(16 "In7.Cu" signal "GND3")
		(18 "In8.Cu" signal "VCC")
		(20 "In9.Cu" signal "VCC1")
		(22 "In10.Cu" signal "GND4")
		(24 "In11.Cu" signal "IN4")
		(26 "In12.Cu" signal "GND5")
		(28 "In13.Cu" signal "IN5")
		(30 "In14.Cu" signal "GND6")
		(32 "In15.Cu" signal "IN6")
		(34 "In16.Cu" signal "GND7")
		(2 "B.Cu" signal "BOTTOM")
		(9 "F.Adhes" user "F.Adhesive")
		(11 "B.Adhes" user "B.Adhesive")
		(13 "F.Paste" user "Package Geometry/Pastemask Top")
		(15 "B.Paste" user "Package Geometry/Pastemask Bottom")
		(5 "F.SilkS" user "Ref Des/Silkscreen Top")
		(7 "B.SilkS" user "Ref Des/Silkscreen Bottom")
		(1 "F.Mask" user "Board Geometry/Soldermask Top")
		(3 "B.Mask" user "Board Geometry/Soldermask Bottom")
		(17 "Dwgs.User" user "User.Drawings")
		(19 "Cmts.User" user "User.Comments")
		(21 "Eco1.User" user "User.Eco1")
		(23 "Eco2.User" user "User.Eco2")
		(25 "Edge.Cuts" user "Board Geometry/Outline")
		(27 "Margin" user)
		(31 "F.CrtYd" user "Package Geometry/Place Bound Top")
		(29 "B.CrtYd" user "Package Geometry/Place Bound Bottom")
		(35 "F.Fab" user "Ref Des/Assembly Top")
		(33 "B.Fab" user "Ref Des/Assembly Bottom")
	)
	(footprint ""
		(layer "B.Cu")
		(at 179.793646 -32.688022 90)
		(property "Reference" "PC2340"
			(at 0 0 90)
			(layer "B.SilkS")
			(hide yes)
			(effects
				(font
					(size 1.27 1.27)
				)
				(justify mirror)
			)
		)
		(property "Value" ""
			(at 0 0 90)
			(layer "B.Fab")
			(effects
				(font
					(size 1.27 1.27)
				)
				(justify mirror)
			)
		)
		(duplicate_pad_numbers_are_jumpers no)
		(fp_line
			(start 0.7874 -0.4064)
			(end -0.7874 -0.4064)
			(stroke
				(width 0.1524)
				(type default)
			)
			(layer "B.SilkS")
		)
		(fp_line
			(start -0.7874 -0.4064)
			(end -0.7874 0.4064)
			(stroke
				(width 0.1524)
				(type default)
			)
			(layer "B.SilkS")
		)
		(fp_line
			(start 0.7874 0.4064)
			(end 0.7874 -0.4064)
			(stroke
				(width 0.1524)
				(type default)
			)
			(layer "B.SilkS")
		)
		(fp_line
			(start -0.7874 0.4064)
			(end 0.7874 0.4064)
			(stroke
				(width 0.1524)
				(type default)
			)
			(layer "B.SilkS")
		)
		(fp_line
			(start 0.67945 -0.305054)
			(end 0.12065 -0.305054)
			(stroke
				(width 0.1)
				(type default)
			)
			(layer "B.Fab")
		)
		(fp_line
			(start 0.12065 -0.305054)
			(end 0.12065 -0.2794)
			(stroke
				(width 0.1)
				(type default)
			)
			(layer "B.Fab")
		)
		(fp_line
			(start -0.12065 -0.3048)
			(end -0.67945 -0.3048)
			(stroke
				(width 0.1)
				(type default)
			)
			(layer "B.Fab")
		)
		(fp_line
			(start -0.67945 -0.3048)
			(end -0.67945 0.3048)
			(stroke
				(width 0.1)
				(type default)
			)
			(layer "B.Fab")
		)
		(fp_line
			(start 0.12065 -0.2794)
			(end -0.12065 -0.2794)
			(stroke
				(width 0.1)
				(type default)
			)
			(layer "B.Fab")
		)
		(fp_line
			(start -0.12065 -0.2794)
			(end -0.12065 -0.3048)
			(stroke
				(width 0.1)
				(type default)
			)
			(layer "B.Fab")
		)
		(fp_line
			(start 0.12065 0.2794)
			(end 0.12065 0.3048)
			(stroke
				(width 0.1)
				(type default)
			)
			(layer "B.Fab")
		)
		(fp_line
			(start -0.120396 0.2794)
			(end 0.12065 0.2794)
			(stroke
				(width 0.1)
				(type default)
			)
			(layer "B.Fab")
		)
		(fp_line
			(start 0.67945 0.3048)
			(end 0.67945 -0.305054)
			(stroke
				(width 0.1)
				(type default)
			)
			(layer "B.Fab")
		)
		(fp_line
			(start 0.12065 0.3048)
			(end 0.67945 0.3048)
			(stroke
				(width 0.1)
				(type default)
			)
			(layer "B.Fab")
		)
		(fp_line
			(start -0.120396 0.3048)
			(end -0.120396 0.2794)
			(stroke
				(width 0.1)
				(type default)
			)
			(layer "B.Fab")
		)
		(fp_line
			(start -0.67945 0.3048)
			(end -0.120396 0.3048)
			(stroke
				(width 0.1)
				(type default)
			)
			(layer "B.Fab")
		)
		(pad "1" smd circle
			(at 0.40005 0 270)
			(size 0 0)
			(layers "B.Cu" "B.Mask" "B.Paste")
			(net "P12V_SCM_ISET_R")
		)
		(pad "2" smd circle
			(at -0.40005 0 270)
			(size 0 0)
			(layers "B.Cu" "B.Mask" "B.Paste")
			(net "GND")
		)
	)
	(footprint ""
		(layer "B.Cu")
		(at 79.260954 -191.358012 90)
		(property "Reference" "PC302_3"
			(at 0 0 90)
			(layer "B.SilkS")
			(hide yes)
			(effects
				(font
					(size 1.27 1.27)
				)
				(justify mirror)
			)
		)
		(property "Value" ""
			(at 0 0 90)
			(layer "B.Fab")
			(effects
				(font
					(size 1.27 1.27)
				)
				(justify mirror)
			)
		)
		(duplicate_pad_numbers_are_jumpers no)
		(fp_line
			(start 1.524 -0.762)
			(end -1.524 -0.762)
			(stroke
				(width 0.1524)
				(type default)
			)
			(layer "B.SilkS")
		)
		(fp_line
			(start -1.524 -0.762)
			(end -1.524 0.762)
			(stroke
				(width 0.1524)
				(type default)
			)
			(layer "B.SilkS")
		)
		(fp_line
			(start 1.524 0.762)
			(end 1.524 -0.762)
			(stroke
				(width 0.1524)
				(type default)
			)
			(layer "B.SilkS")
		)
		(fp_line
			(start -1.524 0.762)
			(end 1.524 0.762)
			(stroke
				(width 0.1524)
				(type default)
			)
			(layer "B.SilkS")
		)
		(fp_line
			(start 1.1049 -0.724916)
			(end 1.1049 0.724916)
			(stroke
				(width 0.1)
				(type default)
			)
			(layer "B.Fab")
		)
		(fp_line
			(start -1.1049 -0.724916)
			(end 1.1049 -0.724916)
			(stroke
				(width 0.1)
				(type default)
			)
			(layer "B.Fab")
		)
		(fp_line
			(start 1.1049 0.724916)
			(end -1.1049 0.724916)
			(stroke
				(width 0.1)
				(type default)
			)
			(layer "B.Fab")
		)
		(fp_line
			(start -1.1049 0.724916)
			(end -1.1049 -0.724916)
			(stroke
				(width 0.1)
				(type default)
			)
			(layer "B.Fab")
		)
		(pad "1" smd rect
			(at 0.889 0 90)
			(size 1.016 1.27)
			(layers "B.Cu" "B.Mask" "B.Paste")
			(net "PVDDCR_CPU0_P1")
		)
		(pad "2" smd rect
			(at -0.889 0 90)
			(size 1.016 1.27)
			(layers "B.Cu" "B.Mask" "B.Paste")
			(net "GND")
		)
	)
	(footprint ""
		(layer "B.Cu")
		(at 109.512862 -388.846568)
		(property "Reference" "C475"
			(at 0 0 0)
			(layer "B.SilkS")
			(hide yes)
			(effects
				(font
					(size 1.27 1.27)
				)
				(justify mirror)
			)
		)
		(property "Value" ""
			(at 0 0 0)
			(layer "B.Fab")
			(effects
				(font
					(size 1.27 1.27)
				)
				(justify mirror)
			)
		)
		(duplicate_pad_numbers_are_jumpers no)
		(fp_line
			(start -1.524 -0.762)
			(end -1.524 0.762)
			(stroke
				(width 0.1524)
				(type default)
			)
			(layer "B.SilkS")
		)
		(fp_line
			(start -1.524 0.762)
			(end 1.524 0.762)
			(stroke
				(width 0.1524)
				(type default)
			)
			(layer "B.SilkS")
		)
		(fp_line
			(start 1.524 -0.762)
			(end -1.524 -0.762)
			(stroke
				(width 0.1524)
				(type default)
			)
			(layer "B.SilkS")
		)
		(fp_line
			(start 1.524 0.762)
			(end 1.524 -0.762)
			(stroke
				(width 0.1524)
				(type default)
			)
			(layer "B.SilkS")
		)
		(fp_line
			(start -1.1049 -0.724916)
			(end 1.1049 -0.724916)
			(stroke
				(width 0.1)
				(type default)
			)
			(layer "B.Fab")
		)
		(fp_line
			(start -1.1049 0.724916)
			(end -1.1049 -0.724916)
			(stroke
				(width 0.1)
				(type default)
			)
			(layer "B.Fab")
		)
		(fp_line
			(start 1.1049 -0.724916)
			(end 1.1049 0.724916)
			(stroke
				(width 0.1)
				(type default)
			)
			(layer "B.Fab")
		)
		(fp_line
			(start 1.1049 0.724916)
			(end -1.1049 0.724916)
			(stroke
				(width 0.1)
				(type default)
			)
			(layer "B.Fab")
		)
		(pad "1" smd rect
			(at 0.889 0)
			(size 1.016 1.27)
			(layers "B.Cu" "B.Mask" "B.Paste")
			(net "P0V9_CPU1_RT3_2A")
		)
		(pad "2" smd rect
			(at -0.889 0)
			(size 1.016 1.27)
			(layers "B.Cu" "B.Mask" "B.Paste")
			(net "GND")
		)
	)
)
